# BASEBOARD_FAB2 (Tioga Pass) — schematic netlist excerpt (pin names and nets, part order shuffled) for the footprints in the layout excerpt that follows; sources: Cadence DE-HDL packaged netlist, KiCad conversion of Wiwynn_Tioga_Pass_MB.brd

R2L25  RES  100.0K 1% CHIP  pkg 0402  page 235 : A = P3V3_STBY ; B = VID_PCH_CORE_PVNN_AUX_VID_1
R6U15  RES  1.0M 1% EMPTY  pkg 0402  page 221 : A = P3V3 ; B = FM_PVTT_ABC_EN_R
C32W3  CAP_A  0.1UF 16V 10% X7R  pkg 0402V  page 185 : A = P1V8_M2 ; B = GND

(kicad_pcb
	(version 20260206)
	(generator "pcbnew")
	(generator_version "10.0")
	(general
		(thickness 1.6)
		(legacy_teardrops no)
	)
	(paper "A4")
	(title_block
		(title "Wiwynn_Tioga_Pass_MB.brd")
		(comment 1 "Tioga Pass / footprints 4592-4594 of 4770")
	)
	(layers
		(0 "F.Cu" signal "TOP")
		(4 "In1.Cu" signal "L2GND")
		(6 "In2.Cu" signal "L3")
		(8 "In3.Cu" signal "L4GND")
		(10 "In4.Cu" signal "L5")
		(12 "In5.Cu" signal "L6GND")
		(14 "In6.Cu" signal "L7VCC")
		(16 "In7.Cu" signal "L8VCC")
		(18 "In8.Cu" signal "L9GND")
		(20 "In9.Cu" signal "L10")
		(22 "In10.Cu" signal "L11GND")
		(24 "In11.Cu" signal "L12")
		(26 "In12.Cu" signal "L13GND")
		(2 "B.Cu" signal "BOTTOM")
		(9 "F.Adhes" user "F.Adhesive")
		(11 "B.Adhes" user "B.Adhesive")
		(13 "F.Paste" user "Package Geometry/Pastemask Top")
		(15 "B.Paste" user "Package Geometry/Pastemask Bottom")
		(5 "F.SilkS" user "Ref Des/Silkscreen Top")
		(7 "B.SilkS" user "Ref Des/Silkscreen Bottom")
		(1 "F.Mask" user "Board Geometry/Soldermask Top")
		(3 "B.Mask" user "Board Geometry/Soldermask Bottom")
		(17 "Dwgs.User" user "User.Drawings")
		(19 "Cmts.User" user "User.Comments")
		(21 "Eco1.User" user "User.Eco1")
		(23 "Eco2.User" user "User.Eco2")
		(25 "Edge.Cuts" user "Board Geometry/Outline")
		(27 "Margin" user)
		(31 "F.CrtYd" user "Package Geometry/Place Bound Top")
		(29 "B.CrtYd" user "Package Geometry/Place Bound Bottom")
		(35 "F.Fab" user "Ref Des/Assembly Top")
		(33 "B.Fab" user "Ref Des/Assembly Bottom")
	)
	(footprint ""
		(layer "B.Cu")
		(at 402.463 -153.289 -90)
		(property "Reference" "R2L25"
			(at 0 0 90)
			(layer "B.SilkS")
			(hide yes)
			(effects
				(font
					(size 1.27 1.27)
				)
				(justify mirror)
			)
		)
		(property "Value" ""
			(at 0 0 90)
			(layer "B.Fab")
			(effects
				(font
					(size 1.27 1.27)
				)
				(justify mirror)
			)
		)
		(duplicate_pad_numbers_are_jumpers no)
		(fp_poly
			(pts
				(xy 0.2794 -0.1016) (xy -0.2794 -0.1016) (xy -0.2794 0.9906) (xy 0.2794 0.9906)
			)
			(stroke
				(width 0)
				(type default)
			)
			(fill no)
			(layer "B.CrtYd")
		)
		(fp_line
			(start -0.2794 0.9906)
			(end -0.2794 -0.1016)
			(stroke
				(width 0.1)
				(type default)
			)
			(layer "B.Fab")
		)
		(fp_line
			(start 0.2794 0.9906)
			(end -0.2794 0.9906)
			(stroke
				(width 0.1)
				(type default)
			)
			(layer "B.Fab")
		)
		(fp_line
			(start -0.2794 -0.1016)
			(end 0.2794 -0.1016)
			(stroke
				(width 0.1)
				(type default)
			)
			(layer "B.Fab")
		)
		(fp_line
			(start 0.2794 -0.1016)
			(end 0.2794 0.9906)
			(stroke
				(width 0.1)
				(type default)
			)
			(layer "B.Fab")
		)
		(pad "1" smd rect
			(at 0 0 90)
			(size 0.508 0.508)
			(layers "B.Cu" "B.Mask" "B.Paste")
			(net "P3V3_STBY")
		)
		(pad "2" smd rect
			(at 0 0.889 90)
			(size 0.508 0.508)
			(layers "B.Cu" "B.Mask" "B.Paste")
			(net "VID_PCH_CORE_PVNN_AUX_VID_1")
		)
		(zone
			(layer "B.Cu")
			(hatch none 0.5)
			(connect_pads
				(clearance 0)
			)
			(min_thickness 0.25)
			(keepout
				(tracks not_allowed)
				(vias allowed)
				(pads allowed)
				(copperpour not_allowed)
				(footprints allowed)
			)
			(placement
				(enabled no)
				(sheetname "")
			)
			(fill
				(thermal_gap 0.5)
				(thermal_bridge_width 0.5)
				(island_removal_mode 0)
			)
			(polygon
				(pts
					(xy 401.828 -153.035) (xy 401.828 -153.543) (xy 402.209 -153.543) (xy 402.209 -153.035)
				)
			)
		)
		(zone
			(layer "B.Cu")
			(hatch none 0.5)
			(connect_pads
				(clearance 0)
			)
			(min_thickness 0.25)
			(keepout
				(tracks allowed)
				(vias not_allowed)
				(pads allowed)
				(copperpour not_allowed)
				(footprints allowed)
			)
			(placement
				(enabled no)
				(sheetname "")
			)
			(fill
				(thermal_gap 0.5)
				(thermal_bridge_width 0.5)
				(island_removal_mode 0)
			)
			(polygon
				(pts
					(xy 402.209 -153.035) (xy 402.209 -153.543) (xy 401.828 -153.543) (xy 401.828 -153.035)
				)
			)
		)
	)
	(footprint ""
		(layer "B.Cu")
		(at 181.339998 2.425192 180)
		(property "Reference" "R6U15"
			(at 0 0 0)
			(layer "B.SilkS")
			(hide yes)
			(effects
				(font
					(size 1.27 1.27)
				)
				(justify mirror)
			)
		)
		(property "Value" ""
			(at 0 0 0)
			(layer "B.Fab")
			(effects
				(font
					(size 1.27 1.27)
				)
				(justify mirror)
			)
		)
		(duplicate_pad_numbers_are_jumpers no)
		(fp_rect
			(start 0.2794 -0.1016)
			(end -0.2794 0.9906)
			(stroke
				(width 0)
				(type default)
			)
			(fill no)
			(layer "B.CrtYd")
		)
		(fp_line
			(start 0.2794 0.9906)
			(end -0.2794 0.9906)
			(stroke
				(width 0.1)
				(type default)
			)
			(layer "B.Fab")
		)
		(fp_line
			(start 0.2794 -0.1016)
			(end 0.2794 0.9906)
			(stroke
				(width 0.1)
				(type default)
			)
			(layer "B.Fab")
		)
		(fp_line
			(start -0.2794 0.9906)
			(end -0.2794 -0.1016)
			(stroke
				(width 0.1)
				(type default)
			)
			(layer "B.Fab")
		)
		(fp_line
			(start -0.2794 -0.1016)
			(end 0.2794 -0.1016)
			(stroke
				(width 0.1)
				(type default)
			)
			(layer "B.Fab")
		)
		(pad "1" smd rect
			(at 0 0)
			(size 0.508 0.508)
			(layers "B.Cu" "B.Mask" "B.Paste")
			(net "P3V3")
		)
		(pad "2" smd rect
			(at 0 0.889)
			(size 0.508 0.508)
			(layers "B.Cu" "B.Mask" "B.Paste")
			(net "FM_PVTT_ABC_EN_R")
		)
		(zone
			(layer "B.Cu")
			(hatch none 0.5)
			(connect_pads
				(clearance 0)
			)
			(min_thickness 0.25)
			(keepout
				(tracks not_allowed)
				(vias allowed)
				(pads allowed)
				(copperpour not_allowed)
				(footprints allowed)
			)
			(placement
				(enabled no)
				(sheetname "")
			)
			(fill
				(thermal_gap 0.5)
				(thermal_bridge_width 0.5)
				(island_removal_mode 0)
			)
			(polygon
				(pts
					(xy 181.085998 2.171192) (xy 181.593998 2.171192) (xy 181.593998 1.790192) (xy 181.085998 1.790192)
				)
			)
		)
		(zone
			(layer "B.Cu")
			(hatch none 0.5)
			(connect_pads
				(clearance 0)
			)
			(min_thickness 0.25)
			(keepout
				(tracks allowed)
				(vias not_allowed)
				(pads allowed)
				(copperpour not_allowed)
				(footprints allowed)
			)
			(placement
				(enabled no)
				(sheetname "")
			)
			(fill
				(thermal_gap 0.5)
				(thermal_bridge_width 0.5)
				(island_removal_mode 0)
			)
			(polygon
				(pts
					(xy 181.085998 2.171192) (xy 181.593998 2.171192) (xy 181.593998 1.790192) (xy 181.085998 1.790192)
				)
			)
		)
	)
	(footprint ""
		(layer "B.Cu")
		(at 389.861806 -8.696452 -90)
		(property "Reference" "C32W3"
			(at 0.8382 -0.67818 270)
			(unlocked yes)
			(layer "B.SilkS")
			(effects
				(font
					(size 0.4064 0.254)
					(thickness 0.1524)
				)
				(justify left mirror)
			)
		)
		(property "Value" ""
			(at 0 0 90)
			(layer "B.Fab")
			(effects
				(font
					(size 1.27 1.27)
				)
				(justify mirror)
			)
		)
		(duplicate_pad_numbers_are_jumpers no)
		(fp_poly
			(pts
				(xy -0.3048 -0.1016) (xy -0.3048 0.9906) (xy 0.3048 0.9906) (xy 0.3048 -0.1016)
			)
			(stroke
				(width 0)
				(type default)
			)
			(fill no)
			(layer "B.CrtYd")
		)
		(fp_line
			(start -0.3048 0.9906)
			(end -0.3048 -0.1016)
			(stroke
				(width 0.1)
				(type default)
			)
			(layer "B.Fab")
		)
		(fp_line
			(start 0.3048 0.9906)
			(end -0.3048 0.9906)
			(stroke
				(width 0.1)
				(type default)
			)
			(layer "B.Fab")
		)
		(fp_line
			(start -0.3048 -0.1016)
			(end 0.3048 -0.1016)
			(stroke
				(width 0.1)
				(type default)
			)
			(layer "B.Fab")
		)
		(fp_line
			(start 0.3048 -0.1016)
			(end 0.3048 0.9906)
			(stroke
				(width 0.1)
				(type default)
			)
			(layer "B.Fab")
		)
		(pad "1" smd rect
			(at 0 0 90)
			(size 0.508 0.508)
			(layers "B.Cu" "B.Mask" "B.Paste")
			(net "P1V8_M2")
		)
		(pad "2" smd rect
			(at 0 0.889 90)
			(size 0.508 0.508)
			(layers "B.Cu" "B.Mask" "B.Paste")
			(net "GND")
		)
		(zone
			(layer "B.Cu")
			(hatch none 0.5)
			(connect_pads
				(clearance 0)
			)
			(min_thickness 0.25)
			(keepout
				(tracks not_allowed)
				(vias allowed)
				(pads allowed)
				(copperpour not_allowed)
				(footprints allowed)
			)
			(placement
				(enabled no)
				(sheetname "")
			)
			(fill
				(thermal_gap 0.5)
				(thermal_bridge_width 0.5)
				(island_removal_mode 0)
			)
			(polygon
				(pts
					(xy 389.226806 -8.442452) (xy 389.226806 -8.950452) (xy 389.607806 -8.950452) (xy 389.607806 -8.442452)
				)
			)
		)
		(zone
			(layer "B.Cu")
			(hatch none 0.5)
			(connect_pads
				(clearance 0)
			)
			(min_thickness 0.25)
			(keepout
				(tracks allowed)
				(vias not_allowed)
				(pads allowed)
				(copperpour not_allowed)
				(footprints allowed)
			)
			(placement
				(enabled no)
				(sheetname "")
			)
			(fill
				(thermal_gap 0.5)
				(thermal_bridge_width 0.5)
				(island_removal_mode 0)
			)
			(polygon
				(pts
					(xy 389.607806 -8.442452) (xy 389.607806 -8.950452) (xy 389.226806 -8.950452) (xy 389.226806 -8.442452)
				)
			)
		)
	)
)
